FILE_TYPE = CONNECTIVITY;
{Allegro Design Entry HDL 16.6-p007 (v16-6-112F) 10/10/2012}
"PAGE_NUMBER" = 149;
0"NC";
1"P3V3_STBY\g";
2"GND\g";
3"GND\g";
4"P1V2_AUX_BMC\g";
5"GND\g";
6"P1V2_AUX_BMC\g";
7"GND\g";
8"P1V2_AUX_BMC\g";
9"GND\g";
10"P3V3_STBY\g";
11"GND\g";
12"P1V2_AUX_BMC\g";
13"P2V5_AUX_BMC\g";
14"GND\g";
15"GND\g";
16"GND\g";
17"P1V2_AUX_BMC\g";
18"GND\g";
19"P1V2_AUX_BMC\g";
20"P3V3_STBY\g";
21"GND\g";
22"BMC_M_VREFCA";
23"BMC_ZQ";
24"BMC_M_MALERT_N";
25"BMC_M_RST_N";
26"BMC_M_CS_N";
27"BMC_M_MACT_N";
28"BMC_M_A0";
29"BMC_M_A1";
30"BMC_M_A2";
31"BMC_M_A4";
32"BMC_M_A5";
33"BMC_M_A3";
34"BMC_M_A6";
35"BMC_M_A7";
36"BMC_M_A8";
37"BMC_M_A9";
38"BMC_M_A10";
39"BMC_M_CKE";
40"BMC_M_CLK_DN";
41"BMC_M_ODT";
42"BMC_M_VREFCA";
43"BMC_M_PAR";
44"FM_HEARTBEAT_LED";
45"FM_HEARTBEAT_LED_A";
46"RST_BMC_DDR3_R_N";
47"FM_BMC_HEARTBEAT_N";
48"BMC_M_CLK_DN";
49"BMC_M_CLK_DP";
50"BMC_M_RST_N";
51"BMC_M_PAR";
52"RST_BMC_DDR3_BUF_IN_N";
53"BMC_M_RAS_N";
54"BMC_M_BG0";
55"BMC_M_A11";
56"BMC_M_A12";
57"BMC_M_A13";
58"BMC_M_WE_N";
59"BMC_M_CAS_N";
60"BMC_M_CLK_DP";
61"FM_HEARTBEAT_LED_K";
62"BMC_M_DQ8";
63"BMC_M_DQ9";
64"BMC_M_DQ10";
65"BMC_M_DQ11";
66"BMC_M_DQ12";
67"BMC_M_DQ13";
68"BMC_M_DQ14";
69"BMC_M_DQ15";
70"BMC_M_DQ0";
71"BMC_M_DQ1";
72"BMC_M_DQ2";
73"BMC_M_DQ3";
74"BMC_M_DQ4";
75"BMC_M_DQ6";
76"BMC_M_DQ5";
77"BMC_M_DQ7";
78"BMC_M_DQS1_DN";
79"BMC_M_DQS0_DN";
80"BMC_M_DQS1_DP";
81"BMC_M_DQS0_DP";
82"BMC_M_DM1";
83"BMC_M_DM0";
84"BMC_M_BA0";
85"BMC_M_BA1";
86"BMC_M_BA0";
87"BMC_M_BA1";
88"BMC_M_BG0";
89"BMC_M_A0";
90"BMC_M_A3";
91"BMC_M_A2";
92"BMC_M_A5";
93"BMC_M_A4";
94"BMC_M_A6";
95"BMC_M_A8";
96"BMC_M_CKE";
97"BMC_M_ODT";
98"BMC_M_RST_N";
99"BMC_M_MALERT_N";
100"BMC_M_CS_N";
101"BMC_M_RAS_N";
102"BMC_M_CAS_N";
103"BMC_M_WE_N";
104"BMC_M_A1";
105"BMC_M_A7";
106"BMC_M_A9";
107"BMC_M_A10";
108"BMC_M_A11";
109"BMC_M_A12";
110"BMC_M_A13";
111"BMC_M_MACT_N";
%"H5AN4G6NAFR-TFC-GP"
"1","(-1850,2625)","0","w_hdl","I1";
;
CDS_SEC"1"
$SEC"1"
CDS_LOCATION"U25W5"
CDS_LMAN_SYM_OUTLINE"-325,1525,325,-1525"
CDS_LIB"w_hdl"
PART_NUMBER"072.00546.0A0U"
PACK_TYPE"MEMORY-G2"
VALUE"H5AN4G6NAFR-TFC-GP"
LOCATION"U25W5";
"BA1"
$PN"N8"85;
"BA0"
$PN"N2"84;
"DML#/DBIL# \B"
$PN"E7"83;
"DMU#/DBIU# \B"
$PN"E2"82;
"DQSL_T"
$PN"G3"81;
"DQSL_C"
$PN"F3"79;
"DQSU_T"
$PN"B7"80;
"DQSU_C"
$PN"A7"78;
"VSSQ<9>"
$PN"H9"11;
"VSSQ<8>"
$PN"H1"11;
"VSSQ<7>"
$PN"F1"11;
"VSSQ<6>"
$PN"E8"11;
"VSSQ<5>"
$PN"E3"11;
"VSSQ<4>"
$PN"D8"11;
"VSSQ<3>"
$PN"D2"11;
"VSSQ<2>"
$PN"C9"11;
"VSSQ<1>"
$PN"A8"11;
"VSSQ<0>"
$PN"A2"11;
"VSS<8>"
$PN"T1"11;
"VSS<7>"
$PN"N1"11;
"VSS<6>"
$PN"M9"11;
"VSS<5>"
$PN"K9"11;
"VSS<4>"
$PN"K1"11;
"VSS<3>"
$PN"G8"11;
"VSS<2>"
$PN"E9"11;
"VSS<1>"
$PN"E1"11;
"VSS<0>"
$PN"B2"11;
"ALERT# \B"
$PN"P9"24;
"RESET# \B"
$PN"P1"25;
"CS# \B"
$PN"L7"26;
"ACT# \B"
$PN"L3"27;
"VPP<1>"
$PN"R9"14;
"CK_C"
$PN"K8"40;
"CK_T"
$PN"K7"60;
"NC#T7"
$PN"T7"0;
"PAR"
$PN"T3"51;
"TEN"
$PN"N9"11;
"BG0"
$PN"M2"54;
"ODT"
$PN"K3"41;
"CKE"
$PN"K2"39;
"ZQ"
$PN"F9"23;
"VREFCA"
$PN"M1"22;
"RAS#/A16 \B"
$PN"L8"53;
"CAS#/A15 \B"
$PN"M8"59;
"WE#/A14 \B"
$PN"L2"58;
"A13"
$PN"T8"57;
"A12/BC# \B"
$PN"M7"56;
"A11"
$PN"T2"55;
"A10/AP"
$PN"M3"38;
"A9"
$PN"R7"37;
"A8"
$PN"R2"36;
"A7"
$PN"R8"35;
"A6"
$PN"P2"34;
"A5"
$PN"P8"32;
"A4"
$PN"N3"31;
"A3"
$PN"N7"33;
"A2"
$PN"R3"30;
"A1"
$PN"P7"29;
"A0"
$PN"P3"28;
"DQL7"
$PN"J7"77;
"DQL6"
$PN"J3"75;
"DQL5"
$PN"H8"76;
"DQL3"
$PN"H7"73;
"DQL2"
$PN"H3"72;
"DQL4"
$PN"H2"74;
"DQL0"
$PN"G2"70;
"DQL1"
$PN"F7"71;
"DQU3"
$PN"C7"65;
"DQU2"
$PN"C3"64;
"DQU1"
$PN"B8"63;
"DQU0"
$PN"A3"62;
"DQU7"
$PN"D7"69;
"DQU6"
$PN"D3"68;
"DQU5"
$PN"C8"67;
"DQU4"
$PN"C2"66;
"VDDQ<9>"
$PN"J8"12;
"VDDQ<8>"
$PN"J2"12;
"VDDQ<7>"
$PN"G9"12;
"VDDQ<6>"
$PN"G1"12;
"VDDQ<5>"
$PN"F8"12;
"VDDQ<4>"
$PN"F2"12;
"VDDQ<3>"
$PN"D9"12;
"VDDQ<2>"
$PN"C1"12;
"VDDQ<1>"
$PN"A9"12;
"VDDQ<0>"
$PN"A1"12;
"VDD<9>"
$PN"T9"12;
"VDD<8>"
$PN"R1"12;
"VDD<7>"
$PN"L9"12;
"VDD<6>"
$PN"L1"12;
"VDD<5>"
$PN"J9"12;
"VDD<4>"
$PN"J1"12;
"VDD<3>"
$PN"G7"12;
"VDD<2>"
$PN"D1"12;
"VDD<1>"
$PN"B9"12;
"VDD<0>"
$PN"B3"12;
"VPP<0>"
$PN"B1"13;
%"P3V3_STBY"
"1","(-6200,2550)","0","mstr_symbols","I108";
;
CDS_LIB"mstr_symbols"
SIZE"1B"
VOLTAGE"3.3V"
BODY_TYPE"PLUMBING"
HDL_POWER"P3V3_STBY";
"G\NAC"1;
%"FET_N_DUAL"
"5","(-5600,2250)","0","mstr_discrete","I109";
;
ROOM"BMC"
SEC_TYPE"SMLF"
BOM_COST"SM_CONTROLLER"
SEC"2"
CDS_LOCATION"Q9E1"
PACK_TYPE"SMLF"
CDS_LIB"mstr_discrete"
CDS_SEC"2"
LOCATION"Q9E1"
VALUE"NTJD4001N"
MATERIAL"FET"
PART_NUMBER"E40049-001";
"GATE <SIZE -1..0>"
$PN"5"44;
"SOURCE <SIZE-1..0>"
$PN"4"2;
"DRAIN <SIZE -1..0>"
$PN"3"61;
%"GND"
"1","(-5600,1925)","0","mstr_symbols","I110";
;
SIZE"1B"
CDS_LIB"mstr_symbols"
VOLTAGE"0.0V"
BODY_TYPE"PLUMBING"
HDL_POWER"GND";
"A\NAC"2;
%"RES"
"2","(-6200,2325)","0","mstr_discrete","I111";
;
SEC_TYPE"0402"
BOM_COST"SM_CONTROLLER"
SEC"1"
ROOM"BMC"
CDS_LOCATION"R9E21"
CDS_LIB"mstr_discrete"
CDS_SEC"1"
WATTAGE"1/16W"
LOCATION"R9E21"
TOLERANCE"1%"
PACK_TYPE"0402"
PART_NUMBER"G21796-072"
MATERIAL"CHIP"
VALUE"4.75K";
"A"
$PN"1"1;
"B"
$PN"2"44;
%"GND"
"1","(-6200,1525)","0","mstr_symbols","I112";
;
CDS_LIB"mstr_symbols"
SIZE"1B"
VOLTAGE"0.0V"
BODY_TYPE"PLUMBING"
HDL_POWER"GND";
"A\NAC"3;
%"FET_N_DUAL"
"5","(-6200,1825)","0","mstr_discrete","I113";
;
BOM_COST"SM_CONTROLLER"
SEC"1"
SEC_TYPE"SMLF"
PACK_TYPE"SMLF"
ROOM"BMC"
CDS_LOCATION"Q9E1"
CDS_LIB"mstr_discrete"
CDS_SEC"1"
PART_NUMBER"E40049-001"
LOCATION"Q9E1"
VALUE"NTJD4001N"
MATERIAL"FET";
"GATE <SIZE -1..0>"
$PN"2"47;
"SOURCE <SIZE-1..0>"
$PN"1"3;
"DRAIN <SIZE -1..0>"
$PN"6"44;
%"W_VCC_CIRCLE"
"1","(-4675,1300)","0","w_power","I119";
;
CDS_LIB"w_power"
CDS_LMAN_SYM_OUTLINE"-100,100,100,-100"
BODY_TYPE"PLUMBING"
HDL_POWER"P1V2_AUX_BMC";
"VCC_CIRCLE \B"4;
%"RES"
"2","(-4675,1100)","2","mstr_discrete","I120";
;
CDS_SEC"1"
$SEC"1"
CDS_LOCATION"R25W119"
CDS_LIB"mstr_discrete"
ROOM"SB_SPI"
BOM_COST"MIO_BIOS_MEM"
NO_XNET_CONNECTION"1"
WATTAGE"1/16W"
LOCATION"R25W119"
VALUE"4.75K"
PART_NUMBER"G21796-072"
PACK_TYPE"0402"
TOLERANCE"1%"
MATERIAL"CHIP";
"A"
$PN"1"4;
"B"
$PN"2"43;
%"GND"
"1","(-4675,425)","0","mstr_symbols","I121";
;
VOLTAGE"0.0V"
SIZE"1B"
CDS_LIB"mstr_symbols"
BODY_TYPE"PLUMBING"
HDL_POWER"GND";
"A\NAC"5;
%"RES"
"2","(-4675,750)","2","mstr_discrete","I122";
;
CDS_SEC"1"
$SEC"1"
CDS_LOCATION"R25W118"
CDS_LIB"mstr_discrete"
ROOM"SB_SPI"
BOM_COST"MIO_BIOS_MEM"
NO_XNET_CONNECTION"1"
LOCATION"R25W118"
PACK_TYPE"0402"
VALUE"4.75K"
TOLERANCE"1%"
MATERIAL"EMPTY"
WATTAGE"1/16W"
PART_NUMBER"G21796-072";
"A"
$PN"1"43;
"B"
$PN"2"5;
%"W_VCC_CIRCLE"
"1","(-6175,1375)","0","w_power","I123";
;
CDS_LMAN_SYM_OUTLINE"-100,100,100,-100"
CDS_LIB"w_power"
BODY_TYPE"PLUMBING"
HDL_POWER"P1V2_AUX_BMC";
"VCC_CIRCLE \B"6;
%"RES"
"2","(-6175,1050)","0","mstr_discrete","I124";
;
CDS_SEC"1"
CDS_LOCATION"R1T30"
ROOM"BMC_MEMORY"
SEC_TYPE"0402"
CDS_LIB"mstr_discrete"
BOM_COST"SM_MEM"
SEC"1"
PART_NUMBER"G21796-026"
MATERIAL"CHIP"
WATTAGE"1/16W"
TOLERANCE"1%"
LOCATION"R1T30"
PACK_TYPE"0402"
VALUE"1.00K";
"A"
$PN"1"6;
"B"
$PN"2"42;
%"RES"
"2","(-6175,625)","0","mstr_discrete","I125";
;
CDS_SEC"1"
CDS_LOCATION"R1T29"
ROOM"BMC_MEMORY"
SEC_TYPE"0402"
CDS_LIB"mstr_discrete"
BOM_COST"SM_MEM"
SEC"1"
TOLERANCE"1%"
VALUE"1.00K"
PACK_TYPE"0402"
WATTAGE"1/16W"
MATERIAL"CHIP"
PART_NUMBER"G21796-026"
LOCATION"R1T29";
"A"
$PN"1"42;
"B"
$PN"2"7;
%"CAP"
"1","(-6450,625)","0","mstr_discrete","I126";
;
CDS_LOCATION"C25W12"
ROOM"BMC_MEMORY"
SEC_TYPE"0402"
CDS_LIB"mstr_discrete"
BOM_COST"SM_MEM"
SEC"1"
CDS_SEC"1"
VOLTAGE"6.3V"
MATERIAL"X6S"
TOLERANCE"10%"
PART_NUMBER"D97712-004"
PACK_TYPE"0402"
VALUE"1.0UF"
LOCATION"C25W12";
"A"
$PN"1"42;
"B"
$PN"2"7;
%"GND"
"1","(-6175,175)","0","mstr_symbols","I127";
;
CDS_LIB"mstr_symbols"
SIZE"1B"
VOLTAGE"0.0V"
BODY_TYPE"PLUMBING"
HDL_POWER"GND";
"A\NAC"7;
%"RES"
"1","(-1375,4600)","0","mstr_discrete","I14";
;
CDS_SEC"1"
ROOM"BMC_MEMORY"
CDS_LOCATION"R9F34"
SEC"1"
BOM_COST"SM_MEM"
CDS_LIB"mstr_discrete"
SEC_TYPE"0402"
PART_NUMBER"G21796-074"
LOCATION"R9F34"
TOLERANCE"1%"
WATTAGE"1/16W"
MATERIAL"CHIP"
VALUE"33.2"
PACK_TYPE"0402";
"B"
$PN"2"50;
"A"
$PN"1"46;
%"W_VCC_CIRCLE"
"1","(-1725,4925)","0","w_power","I15";
;
CDS_LIB"w_power"
CDS_LMAN_SYM_OUTLINE"-100,100,100,-100"
BODY_TYPE"PLUMBING"
HDL_POWER"P1V2_AUX_BMC";
"VCC_CIRCLE \B"8;
%"GND"
"1","(-7900,2750)","0","mstr_symbols","I154";
;
HDL_POWER"GND"
BODY_TYPE"PLUMBING"
SIZE"1B"
VOLTAGE"0.0V"
CDS_LIB"mstr_symbols";
"A\NAC"9;
%"P3V3_STBY"
"1","(-6675,2400)","0","mstr_symbols","I155";
;
SIZE"1B"
CDS_LIB"mstr_symbols"
VOLTAGE"3.3V"
BODY_TYPE"PLUMBING"
HDL_POWER"P3V3_STBY";
"G\NAC"10;
%"RES"
"2","(-6675,2150)","0","mstr_discrete","I156";
;
ROOM"BMC"
CDS_LOCATION"R8B25"
SEC"1"
SEC_TYPE"0402"
BOM_COST"SM_CONTROLLER"
CDS_LIB"mstr_discrete"
CDS_SEC"1"
VALUE"4.75K"
WATTAGE"1/16W"
PART_NUMBER"G21796-072"
PACK_TYPE"0402"
TOLERANCE"1%"
MATERIAL"CHIP"
LOCATION"R8B25";
"A"
$PN"1"10;
"B"
$PN"2"47;
%"CAP"
"1","(-6775,1025)","0","mstr_discrete","I158";
;
CDS_LOCATION"C25W10"
CDS_SEC"1"
SEC"1"
BOM_COST"SM_MEM"
CDS_LIB"mstr_discrete"
SEC_TYPE"0402LF"
ROOM"BMC_MEMORY"
PART_NUMBER"A36096-045"
LOCATION"C25W10"
TOLERANCE"10%"
VOLTAGE"25V"
MATERIAL"X7R"
PACK_TYPE"0402LF"
VALUE"0.01UF";
"A"
$PN"1"6;
"B"
$PN"2"42;
%"CAP"
"1","(-6775,625)","0","mstr_discrete","I159";
;
CDS_LOCATION"C25W11"
CDS_SEC"1"
SEC"1"
BOM_COST"SM_MEM"
CDS_LIB"mstr_discrete"
SEC_TYPE"0402LF"
ROOM"BMC_MEMORY"
LOCATION"C25W11"
VOLTAGE"25V"
MATERIAL"X7R"
PACK_TYPE"0402LF"
VALUE"0.01UF"
PART_NUMBER"A36096-045"
TOLERANCE"10%";
"A"
$PN"1"42;
"B"
$PN"2"7;
%"RES"
"2","(-1725,4775)","0","mstr_discrete","I16";
;
SEC_TYPE"0402"
CDS_LIB"mstr_discrete"
BOM_COST"SM_MEM"
SEC"1"
CDS_LOCATION"R9F29"
ROOM"BMC_MEMORY"
CDS_SEC"1"
VALUE"4.75K"
MATERIAL"CHIP"
LOCATION"R9F29"
WATTAGE"1/16W"
PART_NUMBER"G21796-072"
PACK_TYPE"0402"
TOLERANCE"1%";
"A"
$PN"1"8;
"B"
$PN"2"46;
%"120R2F-GP"
"1","(-7525,4300)","1","w_hdl","I160";
;
CDS_SEC"1"
$SEC"1"
CDS_LOCATION"R25W1"
CDS_LMAN_SYM_OUTLINE"-50,75,50,-75"
CDS_LIB"w_hdl"
PART_NUMBER"64.12005.6DL"
PACK_TYPE"RCL_GP"
VALUE"120R2F-GP"
LOCATION"R25W1";
"2"
$PN"2"96;
"1"
$PN"1"9;
%"120R2F-GP"
"1","(-7525,4250)","1","w_hdl","I161";
;
CDS_SEC"1"
$SEC"1"
CDS_LOCATION"R25W2"
CDS_LIB"w_hdl"
CDS_LMAN_SYM_OUTLINE"-50,75,50,-75"
PART_NUMBER"64.12005.6DL"
PACK_TYPE"RCL_GP"
VALUE"120R2F-GP"
LOCATION"R25W2";
"2"
$PN"2"97;
"1"
$PN"1"9;
%"120R2F-GP"
"1","(-7525,4150)","1","w_hdl","I162";
;
CDS_SEC"1"
$SEC"1"
CDS_LOCATION"R25W4"
CDS_LIB"w_hdl"
CDS_LMAN_SYM_OUTLINE"-50,75,50,-75"
PART_NUMBER"64.12005.6DL"
PACK_TYPE"RCL_GP"
VALUE"120R2F-GP"
LOCATION"R25W4";
"2"
$PN"2"99;
"1"
$PN"1"9;
%"120R2F-GP"
"1","(-7525,4200)","1","w_hdl","I163";
;
CDS_SEC"1"
$SEC"1"
CDS_LOCATION"R25W3"
CDS_LMAN_SYM_OUTLINE"-50,75,50,-75"
CDS_LIB"w_hdl"
PART_NUMBER"64.12005.6DL"
PACK_TYPE"RCL_GP"
VALUE"120R2F-GP"
LOCATION"R25W3";
"2"
$PN"2"98;
"1"
$PN"1"9;
%"120R2F-GP"
"1","(-7525,4100)","1","w_hdl","I164";
;
CDS_SEC"1"
$SEC"1"
CDS_LOCATION"R25W5"
CDS_LMAN_SYM_OUTLINE"-50,75,50,-75"
CDS_LIB"w_hdl"
PART_NUMBER"64.12005.6DL"
PACK_TYPE"RCL_GP"
VALUE"120R2F-GP"
LOCATION"R25W5";
"2"
$PN"2"100;
"1"
$PN"1"9;
%"120R2F-GP"
"1","(-7525,4050)","1","w_hdl","I165";
;
CDS_SEC"1"
$SEC"1"
CDS_LOCATION"R25W6"
CDS_LIB"w_hdl"
CDS_LMAN_SYM_OUTLINE"-50,75,50,-75"
PART_NUMBER"64.12005.6DL"
PACK_TYPE"RCL_GP"
VALUE"120R2F-GP"
LOCATION"R25W6";
"2"
$PN"2"101;
"1"
$PN"1"9;
%"120R2F-GP"
"1","(-7525,4000)","1","w_hdl","I166";
;
CDS_SEC"1"
$SEC"1"
CDS_LOCATION"R25W7"
CDS_LMAN_SYM_OUTLINE"-50,75,50,-75"
CDS_LIB"w_hdl"
PART_NUMBER"64.12005.6DL"
PACK_TYPE"RCL_GP"
VALUE"120R2F-GP"
LOCATION"R25W7";
"2"
$PN"2"102;
"1"
$PN"1"9;
%"120R2F-GP"
"1","(-7525,3950)","1","w_hdl","I167";
;
CDS_SEC"1"
$SEC"1"
CDS_LOCATION"R25W8"
CDS_LIB"w_hdl"
CDS_LMAN_SYM_OUTLINE"-50,75,50,-75"
PART_NUMBER"64.12005.6DL"
PACK_TYPE"RCL_GP"
VALUE"120R2F-GP"
LOCATION"R25W8";
"2"
$PN"2"103;
"1"
$PN"1"9;
%"120R2F-GP"
"1","(-7525,3900)","1","w_hdl","I168";
;
CDS_SEC"1"
$SEC"1"
CDS_LOCATION"R25W9"
CDS_LMAN_SYM_OUTLINE"-50,75,50,-75"
CDS_LIB"w_hdl"
PART_NUMBER"64.12005.6DL"
PACK_TYPE"RCL_GP"
VALUE"120R2F-GP"
LOCATION"R25W9";
"2"
$PN"2"86;
"1"
$PN"1"9;
%"120R2F-GP"
"1","(-7525,3850)","1","w_hdl","I169";
;
CDS_SEC"1"
$SEC"1"
CDS_LOCATION"R25W10"
CDS_LIB"w_hdl"
CDS_LMAN_SYM_OUTLINE"-50,75,50,-75"
PART_NUMBER"64.12005.6DL"
PACK_TYPE"RCL_GP"
VALUE"120R2F-GP"
LOCATION"R25W10";
"2"
$PN"2"87;
"1"
$PN"1"9;
%"120R2F-GP"
"1","(-7525,3750)","1","w_hdl","I170";
;
CDS_SEC"1"
$SEC"1"
CDS_LOCATION"R25W12"
CDS_LIB"w_hdl"
CDS_LMAN_SYM_OUTLINE"-50,75,50,-75"
PART_NUMBER"64.12005.6DL"
PACK_TYPE"RCL_GP"
VALUE"120R2F-GP"
LOCATION"R25W12";
"2"
$PN"2"89;
"1"
$PN"1"9;
%"120R2F-GP"
"1","(-7525,3800)","1","w_hdl","I171";
;
CDS_SEC"1"
$SEC"1"
CDS_LOCATION"R25W11"
CDS_LMAN_SYM_OUTLINE"-50,75,50,-75"
CDS_LIB"w_hdl"
PART_NUMBER"64.12005.6DL"
PACK_TYPE"RCL_GP"
VALUE"120R2F-GP"
LOCATION"R25W11";
"2"
$PN"2"88;
"1"
$PN"1"9;
%"120R2F-GP"
"1","(-7525,3700)","1","w_hdl","I172";
;
CDS_SEC"1"
$SEC"1"
CDS_LOCATION"R25W13"
CDS_LMAN_SYM_OUTLINE"-50,75,50,-75"
CDS_LIB"w_hdl"
PART_NUMBER"64.12005.6DL"
PACK_TYPE"RCL_GP"
VALUE"120R2F-GP"
LOCATION"R25W13";
"2"
$PN"2"104;
"1"
$PN"1"9;
%"120R2F-GP"
"1","(-7525,3550)","1","w_hdl","I173";
;
CDS_SEC"1"
$SEC"1"
CDS_LOCATION"R25W16"
CDS_LIB"w_hdl"
CDS_LMAN_SYM_OUTLINE"-50,75,50,-75"
PART_NUMBER"64.12005.6DL"
PACK_TYPE"RCL_GP"
VALUE"120R2F-GP"
LOCATION"R25W16";
"2"
$PN"2"93;
"1"
$PN"1"9;
%"120R2F-GP"
"1","(-7525,3600)","1","w_hdl","I174";
;
CDS_SEC"1"
$SEC"1"
CDS_LOCATION"R25W15"
CDS_LMAN_SYM_OUTLINE"-50,75,50,-75"
CDS_LIB"w_hdl"
PART_NUMBER"64.12005.6DL"
PACK_TYPE"RCL_GP"
VALUE"120R2F-GP"
LOCATION"R25W15";
"2"
$PN"2"90;
"1"
$PN"1"9;
%"120R2F-GP"
"1","(-7525,3650)","1","w_hdl","I175";
;
CDS_SEC"1"
$SEC"1"
CDS_LOCATION"R25W14"
CDS_LIB"w_hdl"
CDS_LMAN_SYM_OUTLINE"-50,75,50,-75"
PART_NUMBER"64.12005.6DL"
PACK_TYPE"RCL_GP"
VALUE"120R2F-GP"
LOCATION"R25W14";
"2"
$PN"2"91;
"1"
$PN"1"9;
%"120R2F-GP"
"1","(-7525,3250)","1","w_hdl","I176";
;
CDS_SEC"1"
$SEC"1"
CDS_LOCATION"R25W22"
CDS_LIB"w_hdl"
CDS_LMAN_SYM_OUTLINE"-50,75,50,-75"
PART_NUMBER"64.12005.6DL"
PACK_TYPE"RCL_GP"
VALUE"120R2F-GP"
LOCATION"R25W22";
"2"
$PN"2"107;
"1"
$PN"1"9;
%"120R2F-GP"
"1","(-7525,3200)","1","w_hdl","I177";
;
CDS_SEC"1"
$SEC"1"
CDS_LOCATION"R25W23"
CDS_LMAN_SYM_OUTLINE"-50,75,50,-75"
CDS_LIB"w_hdl"
PART_NUMBER"64.12005.6DL"
PACK_TYPE"RCL_GP"
VALUE"120R2F-GP"
LOCATION"R25W23";
"2"
$PN"2"108;
"1"
$PN"1"9;
%"120R2F-GP"
"1","(-7525,3150)","1","w_hdl","I178";
;
CDS_SEC"1"
$SEC"1"
CDS_LOCATION"R25W24"
CDS_LIB"w_hdl"
CDS_LMAN_SYM_OUTLINE"-50,75,50,-75"
PART_NUMBER"64.12005.6DL"
PACK_TYPE"RCL_GP"
VALUE"120R2F-GP"
LOCATION"R25W24";
"2"
$PN"2"109;
"1"
$PN"1"9;
%"120R2F-GP"
"1","(-7525,3100)","1","w_hdl","I179";
;
CDS_SEC"1"
$SEC"1"
CDS_LOCATION"R25W25"
CDS_LMAN_SYM_OUTLINE"-50,75,50,-75"
CDS_LIB"w_hdl"
PART_NUMBER"64.12005.6DL"
PACK_TYPE"RCL_GP"
VALUE"120R2F-GP"
LOCATION"R25W25";
"2"
$PN"2"110;
"1"
$PN"1"9;
%"120R2F-GP"
"1","(-7525,3050)","1","w_hdl","I180";
;
CDS_SEC"1"
$SEC"1"
CDS_LOCATION"R25W26"
PACK_TYPE"RCL_GP"
PART_NUMBER"64.12005.6DL"
CDS_LMAN_SYM_OUTLINE"-50,75,50,-75"
CDS_LIB"w_hdl"
VALUE"120R2F-GP"
LOCATION"R25W26";
"2"
$PN"2"111;
"1"
$PN"1"9;
%"120R2F-GP"
"1","(-7525,3500)","1","w_hdl","I181";
;
CDS_SEC"1"
$SEC"1"
CDS_LOCATION"R25W17"
CDS_LMAN_SYM_OUTLINE"-50,75,50,-75"
CDS_LIB"w_hdl"
PART_NUMBER"64.12005.6DL"
PACK_TYPE"RCL_GP"
VALUE"120R2F-GP"
LOCATION"R25W17";
"2"
$PN"2"92;
"1"
$PN"1"9;
%"120R2F-GP"
"1","(-7525,3450)","1","w_hdl","I182";
;
CDS_SEC"1"
$SEC"1"
CDS_LOCATION"R25W18"
CDS_LIB"w_hdl"
CDS_LMAN_SYM_OUTLINE"-50,75,50,-75"
PART_NUMBER"64.12005.6DL"
PACK_TYPE"RCL_GP"
VALUE"120R2F-GP"
LOCATION"R25W18";
"2"
$PN"2"94;
"1"
$PN"1"9;
%"120R2F-GP"
"1","(-7525,3400)","1","w_hdl","I183";
;
CDS_SEC"1"
$SEC"1"
CDS_LOCATION"R25W19"
CDS_LMAN_SYM_OUTLINE"-50,75,50,-75"
CDS_LIB"w_hdl"
PART_NUMBER"64.12005.6DL"
PACK_TYPE"RCL_GP"
VALUE"120R2F-GP"
LOCATION"R25W19";
"2"
$PN"2"105;
"1"
$PN"1"9;
%"120R2F-GP"
"1","(-7525,3350)","1","w_hdl","I184";
;
CDS_SEC"1"
$SEC"1"
CDS_LOCATION"R25W20"
CDS_LIB"w_hdl"
CDS_LMAN_SYM_OUTLINE"-50,75,50,-75"
PART_NUMBER"64.12005.6DL"
PACK_TYPE"RCL_GP"
VALUE"120R2F-GP"
LOCATION"R25W20";
"2"
$PN"2"95;
"1"
$PN"1"9;
%"120R2F-GP"
"1","(-7525,3300)","1","w_hdl","I185";
;
CDS_SEC"1"
$SEC"1"
CDS_LOCATION"R25W21"
CDS_LIB"w_hdl"
CDS_LMAN_SYM_OUTLINE"-50,75,50,-75"
PART_NUMBER"64.12005.6DL"
PACK_TYPE"RCL_GP"
VALUE"120R2F-GP"
LOCATION"R25W21";
"2"
$PN"2"106;
"1"
$PN"1"9;
%"120R2F-GP"
"1","(-6150,4300)","1","w_hdl","I186";
;
CDS_SEC"1"
$SEC"1"
CDS_LOCATION"R25W27"
CDS_LMAN_SYM_OUTLINE"-50,75,50,-75"
CDS_LIB"w_hdl"
PART_NUMBER"64.12005.6DL"
PACK_TYPE"RCL_GP"
VALUE"120R2F-GP"
LOCATION"R25W27";
"2"
$PN"2"19;
"1"
$PN"1"96;
%"120R2F-GP"
"1","(-6150,4250)","1","w_hdl","I187";
;
CDS_SEC"1"
$SEC"1"
CDS_LOCATION"R25W28"
CDS_LIB"w_hdl"
CDS_LMAN_SYM_OUTLINE"-50,75,50,-75"
PART_NUMBER"64.12005.6DL"
PACK_TYPE"RCL_GP"
VALUE"120R2F-GP"
LOCATION"R25W28";
"2"
$PN"2"19;
"1"
$PN"1"97;
%"120R2F-GP"
"1","(-6150,4150)","1","w_hdl","I188";
;
CDS_SEC"1"
$SEC"1"
CDS_LOCATION"R25W30"
CDS_LIB"w_hdl"
CDS_LMAN_SYM_OUTLINE"-50,75,50,-75"
PART_NUMBER"64.12005.6DL"
PACK_TYPE"RCL_GP"
VALUE"120R2F-GP"
LOCATION"R25W30";
"2"
$PN"2"19;
"1"
$PN"1"99;
%"120R2F-GP"
"1","(-6150,4200)","1","w_hdl","I189";
;
CDS_SEC"1"
$SEC"1"
CDS_LOCATION"R25W29"
CDS_LMAN_SYM_OUTLINE"-50,75,50,-75"
CDS_LIB"w_hdl"
PART_NUMBER"64.12005.6DL"
PACK_TYPE"RCL_GP"
VALUE"120R2F-GP"
LOCATION"R25W29";
"2"
$PN"2"19;
"1"
$PN"1"98;
%"120R2F-GP"
"1","(-6150,4100)","1","w_hdl","I190";
;
CDS_SEC"1"
$SEC"1"
CDS_LOCATION"R25W31"
CDS_LMAN_SYM_OUTLINE"-50,75,50,-75"
CDS_LIB"w_hdl"
PART_NUMBER"64.12005.6DL"
PACK_TYPE"RCL_GP"
VALUE"120R2F-GP"
LOCATION"R25W31";
"2"
$PN"2"19;
"1"
$PN"1"100;
%"120R2F-GP"
"1","(-6150,4050)","1","w_hdl","I191";
;
CDS_SEC"1"
$SEC"1"
CDS_LOCATION"R25W32"
CDS_LIB"w_hdl"
CDS_LMAN_SYM_OUTLINE"-50,75,50,-75"
PART_NUMBER"64.12005.6DL"
PACK_TYPE"RCL_GP"
VALUE"120R2F-GP"
LOCATION"R25W32";
"2"
$PN"2"19;
"1"
$PN"1"101;
%"120R2F-GP"
"1","(-6150,4000)","1","w_hdl","I192";
;
CDS_SEC"1"
$SEC"1"
CDS_LOCATION"R25W33"
CDS_LMAN_SYM_OUTLINE"-50,75,50,-75"
CDS_LIB"w_hdl"
PART_NUMBER"64.12005.6DL"
PACK_TYPE"RCL_GP"
VALUE"120R2F-GP"
LOCATION"R25W33";
"2"
$PN"2"19;
"1"
$PN"1"102;
%"120R2F-GP"
"1","(-6150,3950)","1","w_hdl","I193";
;
CDS_SEC"1"
$SEC"1"
CDS_LOCATION"R25W34"
CDS_LIB"w_hdl"
CDS_LMAN_SYM_OUTLINE"-50,75,50,-75"
PART_NUMBER"64.12005.6DL"
PACK_TYPE"RCL_GP"
VALUE"120R2F-GP"
LOCATION"R25W34";
"2"
$PN"2"19;
"1"
$PN"1"103;
%"120R2F-GP"
"1","(-6150,3900)","1","w_hdl","I194";
;
CDS_SEC"1"
$SEC"1"
CDS_LOCATION"R25W35"
CDS_LMAN_SYM_OUTLINE"-50,75,50,-75"
CDS_LIB"w_hdl"
PART_NUMBER"64.12005.6DL"
PACK_TYPE"RCL_GP"
VALUE"120R2F-GP"
LOCATION"R25W35";
"2"
$PN"2"19;
"1"
$PN"1"86;
%"120R2F-GP"
"1","(-6150,3850)","1","w_hdl","I195";
;
CDS_SEC"1"
$SEC"1"
CDS_LOCATION"R25W36"
CDS_LIB"w_hdl"
CDS_LMAN_SYM_OUTLINE"-50,75,50,-75"
PART_NUMBER"64.12005.6DL"
PACK_TYPE"RCL_GP"
VALUE"120R2F-GP"
LOCATION"R25W36";
"2"
$PN"2"19;
"1"
$PN"1"87;
%"120R2F-GP"
"1","(-6150,3800)","1","w_hdl","I196";
;
CDS_SEC"1"
$SEC"1"
CDS_LOCATION"R25W37"
CDS_LMAN_SYM_OUTLINE"-50,75,50,-75"
CDS_LIB"w_hdl"
PART_NUMBER"64.12005.6DL"
PACK_TYPE"RCL_GP"
VALUE"120R2F-GP"
LOCATION"R25W37";
"2"
$PN"2"19;
"1"
$PN"1"88;
%"120R2F-GP"
"1","(-6150,3750)","1","w_hdl","I197";
;
CDS_SEC"1"
$SEC"1"
CDS_LOCATION"R25W38"
CDS_LIB"w_hdl"
CDS_LMAN_SYM_OUTLINE"-50,75,50,-75"
PART_NUMBER"64.12005.6DL"
PACK_TYPE"RCL_GP"
VALUE"120R2F-GP"
LOCATION"R25W38";
"2"
$PN"2"19;
"1"
$PN"1"89;
%"120R2F-GP"
"1","(-6150,3700)","1","w_hdl","I198";
;
CDS_SEC"1"
$SEC"1"
CDS_LOCATION"R25W39"
CDS_LMAN_SYM_OUTLINE"-50,75,50,-75"
CDS_LIB"w_hdl"
PART_NUMBER"64.12005.6DL"
PACK_TYPE"RCL_GP"
VALUE"120R2F-GP"
LOCATION"R25W39";
"2"
$PN"2"19;
"1"
$PN"1"104;
%"120R2F-GP"
"1","(-6150,3600)","1","w_hdl","I199";
;
CDS_SEC"1"
$SEC"1"
CDS_LOCATION"R25W41"
CDS_LMAN_SYM_OUTLINE"-50,75,50,-75"
CDS_LIB"w_hdl"
PART_NUMBER"64.12005.6DL"
PACK_TYPE"RCL_GP"
VALUE"120R2F-GP"
LOCATION"R25W41";
"2"
$PN"2"19;
"1"
$PN"1"90;
%"120R2F-GP"
"1","(-6150,3650)","1","w_hdl","I200";
;
CDS_SEC"1"
$SEC"1"
CDS_LOCATION"R25W40"
CDS_LIB"w_hdl"
CDS_LMAN_SYM_OUTLINE"-50,75,50,-75"
PART_NUMBER"64.12005.6DL"
PACK_TYPE"RCL_GP"
VALUE"120R2F-GP"
LOCATION"R25W40";
"2"
$PN"2"19;
"1"
$PN"1"91;
%"120R2F-GP"
"1","(-6150,3550)","1","w_hdl","I201";
;
CDS_SEC"1"
$SEC"1"
CDS_LOCATION"R25W42"
CDS_LIB"w_hdl"
CDS_LMAN_SYM_OUTLINE"-50,75,50,-75"
PART_NUMBER"64.12005.6DL"
PACK_TYPE"RCL_GP"
VALUE"120R2F-GP"
LOCATION"R25W42";
"2"
$PN"2"19;
"1"
$PN"1"93;
%"120R2F-GP"
"1","(-6150,3500)","1","w_hdl","I202";
;
CDS_SEC"1"
$SEC"1"
CDS_LOCATION"R25W43"
CDS_LMAN_SYM_OUTLINE"-50,75,50,-75"
CDS_LIB"w_hdl"
PART_NUMBER"64.12005.6DL"
PACK_TYPE"RCL_GP"
VALUE"120R2F-GP"
LOCATION"R25W43";
"2"
$PN"2"19;
"1"
$PN"1"92;
%"120R2F-GP"
"1","(-6150,3450)","1","w_hdl","I203";
;
CDS_SEC"1"
$SEC"1"
CDS_LOCATION"R25W44"
CDS_LIB"w_hdl"
CDS_LMAN_SYM_OUTLINE"-50,75,50,-75"
PART_NUMBER"64.12005.6DL"
PACK_TYPE"RCL_GP"
VALUE"120R2F-GP"
LOCATION"R25W44";
"2"
$PN"2"19;
"1"
$PN"1"94;
%"120R2F-GP"
"1","(-6150,3400)","1","w_hdl","I204";
;
CDS_SEC"1"
$SEC"1"
CDS_LOCATION"R25W45"
CDS_LMAN_SYM_OUTLINE"-50,75,50,-75"
CDS_LIB"w_hdl"
PART_NUMBER"64.12005.6DL"
PACK_TYPE"RCL_GP"
VALUE"120R2F-GP"
LOCATION"R25W45";
"2"
$PN"2"19;
"1"
$PN"1"105;
%"120R2F-GP"
"1","(-6150,3350)","1","w_hdl","I205";
;
CDS_SEC"1"
$SEC"1"
CDS_LOCATION"R25W46"
CDS_LIB"w_hdl"
CDS_LMAN_SYM_OUTLINE"-50,75,50,-75"
PART_NUMBER"64.12005.6DL"
PACK_TYPE"RCL_GP"
VALUE"120R2F-GP"
LOCATION"R25W46";
"2"
$PN"2"19;
"1"
$PN"1"95;
%"120R2F-GP"
"1","(-6150,3300)","1","w_hdl","I206";
;
CDS_SEC"1"
$SEC"1"
CDS_LOCATION"R25W47"
CDS_LIB"w_hdl"
CDS_LMAN_SYM_OUTLINE"-50,75,50,-75"
PART_NUMBER"64.12005.6DL"
PACK_TYPE"RCL_GP"
VALUE"120R2F-GP"
LOCATION"R25W47";
"2"
$PN"2"19;
"1"
$PN"1"106;
%"120R2F-GP"
"1","(-6150,3250)","1","w_hdl","I207";
;
CDS_SEC"1"
$SEC"1"
CDS_LOCATION"R25W48"
CDS_LIB"w_hdl"
CDS_LMAN_SYM_OUTLINE"-50,75,50,-75"
PART_NUMBER"64.12005.6DL"
PACK_TYPE"RCL_GP"
VALUE"120R2F-GP"
LOCATION"R25W48";
"2"
$PN"2"19;
"1"
$PN"1"107;
%"120R2F-GP"
"1","(-6150,3200)","1","w_hdl","I208";
;
CDS_SEC"1"
$SEC"1"
CDS_LOCATION"R25W49"
CDS_LMAN_SYM_OUTLINE"-50,75,50,-75"
CDS_LIB"w_hdl"
PART_NUMBER"64.12005.6DL"
PACK_TYPE"RCL_GP"
VALUE"120R2F-GP"
LOCATION"R25W49";
"2"
$PN"2"19;
"1"
$PN"1"108;
%"120R2F-GP"
"1","(-6150,3150)","1","w_hdl","I209";
;
CDS_SEC"1"
$SEC"1"
CDS_LOCATION"R25W50"
CDS_LIB"w_hdl"
CDS_LMAN_SYM_OUTLINE"-50,75,50,-75"
PART_NUMBER"64.12005.6DL"
PACK_TYPE"RCL_GP"
VALUE"120R2F-GP"
LOCATION"R25W50";
"2"
$PN"2"19;
"1"
$PN"1"109;
%"120R2F-GP"
"1","(-6150,3100)","1","w_hdl","I210";
;
CDS_SEC"1"
$SEC"1"
CDS_LOCATION"R25W51"
CDS_LMAN_SYM_OUTLINE"-50,75,50,-75"
CDS_LIB"w_hdl"
PART_NUMBER"64.12005.6DL"
PACK_TYPE"RCL_GP"
VALUE"120R2F-GP"
LOCATION"R25W51";
"2"
$PN"2"19;
"1"
$PN"1"110;
%"120R2F-GP"
"1","(-6150,3050)","1","w_hdl","I211";
;
CDS_SEC"1"
$SEC"1"
CDS_LOCATION"R25W52"
PACK_TYPE"RCL_GP"
PART_NUMBER"64.12005.6DL"
CDS_LMAN_SYM_OUTLINE"-50,75,50,-75"
CDS_LIB"w_hdl"
VALUE"120R2F-GP"
LOCATION"R25W52";
"2"
$PN"2"19;
"1"
$PN"1"111;
%"120R2F-GP"
"1","(-3550,775)","4","w_hdl","I212";
;
CDS_SEC"1"
$SEC"1"
CDS_LOCATION"R1T28"
PACK_TYPE"RCL_GP"
PART_NUMBER"64.12005.6DL"
CDS_LMAN_SYM_OUTLINE"-50,75,50,-75"
CDS_LIB"w_hdl"
LOCATION"R1T28"
VALUE"120R2F-GP";
"2"
$PN"2"49;
"1"
$PN"1"48;
%"GND"
"1","(-1150,1050)","0","mstr_symbols","I33";
;
CDS_LIB"mstr_symbols"
SIZE"1B"
VOLTAGE"0.0V"
BODY_TYPE"PLUMBING"
HDL_POWER"GND";
"A\NAC"11;
%"TTL1G07_A"
"1","(-2475,4600)","0","mstr_ttl","I34";
;
CDS_SEC"1"
ROOM"BMC_MEMORY"
CDS_LOCATION"U9F3"
SEC"1"
SEC_TYPE"SOP"
CDS_LIB"mstr_ttl"
PACK_TYPE"SOP"
MATERIAL"IC"
PART_NUMBER"C88419-001"
POWER_GROUP"VCC=P3V3_STBY;GND=GND"
LOCATION"U9F3"
VALUE"74LVC1G07";
"Y"
$PN"4"46;
"A"
$PN"2"52;
%"W_VCC_CIRCLE"
"1","(-2600,4050)","0","w_power","I35";
;
CDS_LMAN_SYM_OUTLINE"-100,100,100,-100"
CDS_LIB"w_power"
BODY_TYPE"PLUMBING"
HDL_POWER"P1V2_AUX_BMC";
"VCC_CIRCLE \B"12;
%"CAP"
"1","(-4025,4700)","0","mstr_discrete","I37";
;
CDS_SEC"1"
$SEC"1"
CDS_LOCATION"C25W16"
BOM_COST"SM_CONTROLLER"
ROOM"BMC"
CDS_LIB"mstr_discrete"
LOCATION"C25W16"
VOLTAGE"50V"
VALUE"100.0PF"
PART_NUMBER"A36095-026"
PACK_TYPE"0402LF"
TOLERANCE"5%"
MATERIAL"COG";
"A"
$PN"1"17;
"B"
$PN"2"18;
%"SC1U16V3KX-2GP"
"1","(-4450,4700)","0","w_hdl","I38";
;
CDS_SEC"1"
$SEC"1"
CDS_LOCATION"C25W17"
PACK_TYPE"SMD-BCG"
PART_NUMBER"78.10521.5BL"
CDS_LMAN_SYM_OUTLINE"-50,25,50,-25"
CDS_LIB"w_hdl"
LOCATION"C25W17"
VALUE"SC1U16V3KX-2GP";
"2"
$PN"2"18;
"1"
$PN"1"17;
%"SCD1U16V2KX-3GP"
"1","(-3050,3075)","0","w_hdl","I39";
;
CDS_SEC"1"
$SEC"1"
CDS_LOCATION"C25W15"
PART_NUMBER"78.10421.2FL"
PACK_TYPE"SMD-BCG"
CDS_LMAN_SYM_OUTLINE"-50,25,50,-25"
CDS_LIB"w_hdl"
LOCATION"C25W15"
VALUE"SCD1U16V2KX-3GP";
"2"
$PN"2"14;
"1"
$PN"1"13;
%"W_VCC_CIRCLE"
"1","(-3400,3325)","0","w_power","I40";
;
CDS_LIB"w_power"
CDS_LMAN_SYM_OUTLINE"-100,100,100,-100"
BODY_TYPE"PLUMBING"
HDL_POWER"P2V5_AUX_BMC";
"VCC_CIRCLE \B"13;
%"SCD1U16V2KX-3GP"
"1","(-3400,3075)","0","w_hdl","I44";
;
CDS_SEC"1"
$SEC"1"
CDS_LOCATION"C25W14"
CDS_LMAN_SYM_OUTLINE"-50,25,50,-25"
CDS_LIB"w_hdl"
PART_NUMBER"78.10421.2FL"
PACK_TYPE"SMD-BCG"
VALUE"SCD1U16V2KX-3GP"
LOCATION"C25W14";
"2"
$PN"2"14;
"1"
$PN"1"13;
%"GND"
"1","(-3400,2825)","0","mstr_symbols","I45";
;
VOLTAGE"0.0V"
CDS_LIB"mstr_symbols"
SIZE"1B"
BODY_TYPE"PLUMBING"
HDL_POWER"GND";
"A\NAC"14;
%"RES"
"2","(-3550,2425)","0","mstr_discrete","I55";
;
CDS_SEC"1"
$SEC"1"
CDS_LOCATION"R25W117"
PART_NUMBER"G21796-294"
WATTAGE"1/16W"
CDS_LIB"mstr_discrete"
ROOM"BMC_MEMORY"
BOM_COST"SM_MEM"
VALUE"240"
TOLERANCE"1.0%"
LOCATION"R25W117"
MATERIAL"CHIP"
PACK_TYPE"0402";
"A"
$PN"1"23;
"B"
$PN"2"15;
%"GND"
"1","(-3550,2050)","0","mstr_symbols","I56";
;
HDL_POWER"GND"
BODY_TYPE"PLUMBING"
VOLTAGE"0.0V"
CDS_LIB"mstr_symbols"
SIZE"1B";
"A\NAC"15;
%"CAP"
"1","(-3800,2475)","0","mstr_discrete","I65";
;
CDS_SEC"1"
$SEC"1"
CDS_LOCATION"C25W13"
BOM_COST"SM_CONTROLLER"
ROOM"BMC"
CDS_LIB"mstr_discrete"
PART_NUMBER"A36096-030"
MATERIAL"X7R"
TOLERANCE"10%"
LOCATION"C25W13"
VALUE"0.1UF"
VOLTAGE"16V"
PACK_TYPE"0402LF";
"A"
$PN"1"22;
"B"
$PN"2"16;
%"GND"
"1","(-3800,2050)","0","mstr_symbols","I66";
;
VOLTAGE"0.0V"
CDS_LIB"mstr_symbols"
SIZE"1B"
BODY_TYPE"PLUMBING"
HDL_POWER"GND";
"A\NAC"16;
%"W_VCC_CIRCLE"
"1","(-4950,4900)","0","w_power","I67";
;
CDS_LIB"w_power"
CDS_LMAN_SYM_OUTLINE"-100,100,100,-100"
BODY_TYPE"PLUMBING"
HDL_POWER"P1V2_AUX_BMC";
"VCC_CIRCLE \B"17;
%"SC1U16V3KX-2GP"
"1","(-4775,4700)","0","w_hdl","I68";
;
CDS_SEC"1"
$SEC"1"
CDS_LOCATION"C25W18"
CDS_LMAN_SYM_OUTLINE"-50,25,50,-25"
CDS_LIB"w_hdl"
PART_NUMBER"78.10521.5BL"
PACK_TYPE"SMD-BCG"
LOCATION"C25W18"
VALUE"SC1U16V3KX-2GP";
"2"
$PN"2"18;
"1"
$PN"1"17;
%"SC4D7U10V3KX-GP"
"1","(-4950,4700)","0","w_hdl","I69";
;
CDS_SEC"1"
$SEC"1"
CDS_LOCATION"C25W19"
PART_NUMBER"78.47523.5BL"
PACK_TYPE"SMD-BCG"
CDS_LMAN_SYM_OUTLINE"-50,25,50,-25"
CDS_LIB"w_hdl"
VALUE"SC4D7U10V3KX-GP"
LOCATION"C25W19";
"2"
$PN"2"18;
"1"
$PN"1"17;
%"GND"
"1","(-4950,4425)","0","mstr_symbols","I70";
;
VOLTAGE"0.0V"
SIZE"1B"
CDS_LIB"mstr_symbols"
BODY_TYPE"PLUMBING"
HDL_POWER"GND";
"A\NAC"18;
%"CAP"
"1","(-5300,4300)","1","mstr_discrete","I71";
;
CDS_SEC"1"
$SEC"1"
CDS_LOCATION"C25W1"
ROOM"VDDQ_KLM_PWR_VR"
CDS_LIB"mstr_discrete"
LOCATION"C25W1"
VALUE"1.0UF"
PART_NUMBER"D97712-011"
MATERIAL"X6S"
PACK_TYPE"0402"
VOLTAGE"16V"
TOLERANCE"10%";
"A"
$PN"1"19;
"B"
$PN"2"21;
%"CAP"
"1","(-5300,4050)","1","mstr_discrete","I72";
;
CDS_SEC"1"
$SEC"1"
CDS_LOCATION"C25W2"
ROOM"VDDQ_KLM_PWR_VR"
CDS_LIB"mstr_discrete"
MATERIAL"X6S"
TOLERANCE"10%"
LOCATION"C25W2"
VALUE"1.0UF"
PACK_TYPE"0402"
VOLTAGE"16V"
PART_NUMBER"D97712-011";
"A"
$PN"1"19;
"B"
$PN"2"21;
%"CAP"
"1","(-5300,3800)","1","mstr_discrete","I73";
;
CDS_SEC"1"
$SEC"1"
CDS_LOCATION"C25W3"
CDS_LIB"mstr_discrete"
ROOM"VDDQ_KLM_PWR_VR"
PART_NUMBER"D97712-011"
VOLTAGE"16V"
VALUE"1.0UF"
TOLERANCE"10%"
LOCATION"C25W3"
MATERIAL"X6S"
PACK_TYPE"0402";
"A"
$PN"1"19;
"B"
$PN"2"21;
%"CAP"
"1","(-5300,3550)","1","mstr_discrete","I74";
;
CDS_SEC"1"
$SEC"1"
CDS_LOCATION"C25W4"
CDS_LIB"mstr_discrete"
ROOM"VDDQ_KLM_PWR_VR"
LOCATION"C25W4"
VALUE"1.0UF"
MATERIAL"X6S"
PACK_TYPE"0402"
PART_NUMBER"D97712-011"
TOLERANCE"10%"
VOLTAGE"16V";
"A"
$PN"1"19;
"B"
$PN"2"21;
%"W_VCC_CIRCLE"
"1","(-5575,4525)","0","w_power","I75";
;
CDS_LIB"w_power"
CDS_LMAN_SYM_OUTLINE"-100,100,100,-100"
BODY_TYPE"PLUMBING"
HDL_POWER"P1V2_AUX_BMC";
"VCC_CIRCLE \B"19;
%"P3V3_STBY"
"1","(-4550,2825)","0","mstr_symbols","I93";
;
SIZE"1B"
CDS_LIB"mstr_symbols"
VOLTAGE"3.3V"
BODY_TYPE"PLUMBING"
HDL_POWER"P3V3_STBY";
"G\NAC"20;
%"RES"
"1","(-4800,2625)","0","mstr_discrete","I94";
;
SEC"1"
BOM_COST"SM_CONTROLLER"
SEC_TYPE"0402"
ROOM"BMC"
CDS_LIB"mstr_discrete"
CDS_LOCATION"R9E24"
CDS_SEC"1"
TOLERANCE"1.0%"
LOCATION"R9E24"
VALUE"221"
MATERIAL"CHIP"
WATTAGE"1/16W"
PACK_TYPE"0402"
PART_NUMBER"G21796-271";
"B"
$PN"2"20;
"A"
$PN"1"45;
%"GND"
"1","(-5000,2925)","0","mstr_symbols","I95";
;
CDS_LIB"mstr_symbols"
SIZE"1B"
VOLTAGE"0.0V"
BODY_TYPE"PLUMBING"
HDL_POWER"GND";
"A\NAC"21;
%"CAP"
"1","(-5300,3300)","1","mstr_discrete","I96";
;
CDS_SEC"1"
$SEC"1"
CDS_LOCATION"C25W5"
CDS_LIB"mstr_discrete"
ROOM"VDDQ_KLM_PWR_VR"
MATERIAL"X6S"
PART_NUMBER"D97712-011"
PACK_TYPE"0402"
VOLTAGE"16V"
TOLERANCE"10%"
LOCATION"C25W5"
VALUE"1.0UF";
"A"
$PN"1"19;
"B"
$PN"2"21;
%"CAP"
"1","(-5300,3050)","1","mstr_discrete","I97";
;
CDS_SEC"1"
$SEC"1"
CDS_LOCATION"C25W6"
CDS_LIB"mstr_discrete"
ROOM"VDDQ_KLM_PWR_VR"
PART_NUMBER"D97712-011"
PACK_TYPE"0402"
TOLERANCE"10%"
VOLTAGE"16V"
MATERIAL"X6S"
VALUE"1.0UF"
LOCATION"C25W6";
"A"
$PN"1"19;
"B"
$PN"2"21;
%"LED"
"3","(-5400,2625)","0","mstr_discrete","I98";
;
BOM_COST"SM_CONTROLLER"
SEC_TYPE"A1LF"
PACK_TYPE"A1LF"
ROOM"BMC"
CDS_LOCATION"DS9E1"
SEC"1"
CDS_LIB"mstr_discrete"
CDS_SEC"1"
LOCATION"DS9E1"
MATERIAL"IC"
COLOR"GREEN"
PART_NUMBER"C97278-010";
"A"
$PN"1"45;
"C"
$PN"2"61;
END.
